# S9S_MB_2U (Grand Teton) — schematic netlist excerpt (pin names and nets, part order shuffled) for the footprints in the layout excerpt that follows; sources: Cadence DE-HDL packaged netlist, KiCad conversion of 03242023_DA0F0TMBIJ0_F0T_Motherboard_J_brd_V01_OCP.brd

R238  Q_RES  1.5K 1% CHIP  pkg 0402LF  page 121 : A = H_CPU1_THERMTRIP_LVC1_R_N ; B = H_CPU1_THERMTRIP_VT_R_N
R2311  Q_RES  1K 1% CHIP  pkg 0402LF  page 236 : A = PCA9543_S3M_ADDR0 ; B = GND

(kicad_pcb
	(version 20260206)
	(generator "pcbnew")
	(generator_version "10.0")
	(general
		(thickness 1.6)
		(legacy_teardrops no)
	)
	(paper "A4")
	(title_block
		(title "03242023_DA0F0TMBIJ0_F0T_Motherboard_J_brd_V01_OCP.brd")
		(comment 1 "Grand Teton / footprints 1454-1455 of 6105")
	)
	(layers
		(0 "F.Cu" signal "TOP")
		(4 "In1.Cu" signal "GND")
		(6 "In2.Cu" signal "IN1")
		(8 "In3.Cu" signal "GND1")
		(10 "In4.Cu" signal "IN2")
		(12 "In5.Cu" signal "GND2")
		(14 "In6.Cu" signal "IN3")
		(16 "In7.Cu" signal "GND3")
		(18 "In8.Cu" signal "VCC")
		(20 "In9.Cu" signal "VCC1")
		(22 "In10.Cu" signal "GND4")
		(24 "In11.Cu" signal "IN4")
		(26 "In12.Cu" signal "GND5")
		(28 "In13.Cu" signal "IN5")
		(30 "In14.Cu" signal "GND6")
		(32 "In15.Cu" signal "IN6")
		(34 "In16.Cu" signal "GND7")
		(2 "B.Cu" signal "BOTTOM")
		(9 "F.Adhes" user "F.Adhesive")
		(11 "B.Adhes" user "B.Adhesive")
		(13 "F.Paste" user "Package Geometry/Pastemask Top")
		(15 "B.Paste" user "Package Geometry/Pastemask Bottom")
		(5 "F.SilkS" user "Ref Des/Silkscreen Top")
		(7 "B.SilkS" user "Ref Des/Silkscreen Bottom")
		(1 "F.Mask" user "Board Geometry/Soldermask Top")
		(3 "B.Mask" user "Board Geometry/Soldermask Bottom")
		(17 "Dwgs.User" user "User.Drawings")
		(19 "Cmts.User" user "User.Comments")
		(21 "Eco1.User" user "User.Eco1")
		(23 "Eco2.User" user "User.Eco2")
		(25 "Edge.Cuts" user "Board Geometry/Outline")
		(27 "Margin" user)
		(31 "F.CrtYd" user "Package Geometry/Place Bound Top")
		(29 "B.CrtYd" user "Package Geometry/Place Bound Bottom")
		(35 "F.Fab" user "Ref Des/Assembly Top")
		(33 "B.Fab" user "Ref Des/Assembly Bottom")
	)
	(footprint ""
		(layer "F.Cu")
		(at 157.00121 -70.26402 -90)
		(property "Reference" "R2311"
			(at 0 0 270)
			(layer "F.SilkS")
			(hide yes)
			(effects
				(font
					(size 1.27 1.27)
				)
			)
		)
		(property "Value" ""
			(at 0 0 270)
			(layer "F.Fab")
			(effects
				(font
					(size 1.27 1.27)
				)
			)
		)
		(duplicate_pad_numbers_are_jumpers no)
		(fp_line
			(start -0.7874 0.4064)
			(end -0.7874 -0.4064)
			(stroke
				(width 0.1524)
				(type default)
			)
			(layer "F.SilkS")
		)
		(fp_line
			(start 0.7874 0.4064)
			(end -0.7874 0.4064)
			(stroke
				(width 0.1524)
				(type default)
			)
			(layer "F.SilkS")
		)
		(fp_line
			(start -0.7874 -0.4064)
			(end 0.7874 -0.4064)
			(stroke
				(width 0.1524)
				(type default)
			)
			(layer "F.SilkS")
		)
		(fp_line
			(start 0.7874 -0.4064)
			(end 0.7874 0.4064)
			(stroke
				(width 0.1524)
				(type default)
			)
			(layer "F.SilkS")
		)
		(fp_line
			(start -0.67945 0.3048)
			(end -0.67945 -0.305054)
			(stroke
				(width 0.1)
				(type default)
			)
			(layer "F.Fab")
		)
		(fp_line
			(start -0.12065 0.3048)
			(end -0.67945 0.3048)
			(stroke
				(width 0.1)
				(type default)
			)
			(layer "F.Fab")
		)
		(fp_line
			(start 0.120396 0.3048)
			(end 0.120396 0.2794)
			(stroke
				(width 0.1)
				(type default)
			)
			(layer "F.Fab")
		)
		(fp_line
			(start 0.67945 0.3048)
			(end 0.120396 0.3048)
			(stroke
				(width 0.1)
				(type default)
			)
			(layer "F.Fab")
		)
		(fp_line
			(start -0.12065 0.2794)
			(end -0.12065 0.3048)
			(stroke
				(width 0.1)
				(type default)
			)
			(layer "F.Fab")
		)
		(fp_line
			(start 0.120396 0.2794)
			(end -0.12065 0.2794)
			(stroke
				(width 0.1)
				(type default)
			)
			(layer "F.Fab")
		)
		(fp_line
			(start -0.12065 -0.2794)
			(end 0.12065 -0.2794)
			(stroke
				(width 0.1)
				(type default)
			)
			(layer "F.Fab")
		)
		(fp_line
			(start 0.12065 -0.2794)
			(end 0.12065 -0.3048)
			(stroke
				(width 0.1)
				(type default)
			)
			(layer "F.Fab")
		)
		(fp_line
			(start 0.12065 -0.3048)
			(end 0.67945 -0.3048)
			(stroke
				(width 0.1)
				(type default)
			)
			(layer "F.Fab")
		)
		(fp_line
			(start 0.67945 -0.3048)
			(end 0.67945 0.3048)
			(stroke
				(width 0.1)
				(type default)
			)
			(layer "F.Fab")
		)
		(fp_line
			(start -0.67945 -0.305054)
			(end -0.12065 -0.305054)
			(stroke
				(width 0.1)
				(type default)
			)
			(layer "F.Fab")
		)
		(fp_line
			(start -0.12065 -0.305054)
			(end -0.12065 -0.2794)
			(stroke
				(width 0.1)
				(type default)
			)
			(layer "F.Fab")
		)
		(pad "1" smd circle
			(at -0.40005 0 270)
			(size 0 0)
			(layers "F.Cu" "F.Mask" "F.Paste")
			(net "PCA9543_S3M_ADDR0")
		)
		(pad "2" smd circle
			(at 0.40005 0 270)
			(size 0 0)
			(layers "F.Cu" "F.Mask" "F.Paste")
			(net "GND")
		)
	)
	(footprint ""
		(layer "F.Cu")
		(at 125.65888 -92.674948 90)
		(property "Reference" "R238"
			(at 0 0 90)
			(layer "F.SilkS")
			(hide yes)
			(effects
				(font
					(size 1.27 1.27)
				)
			)
		)
		(property "Value" ""
			(at 0 0 90)
			(layer "F.Fab")
			(effects
				(font
					(size 1.27 1.27)
				)
			)
		)
		(duplicate_pad_numbers_are_jumpers no)
		(fp_line
			(start 0.7874 -0.4064)
			(end 0.7874 0.4064)
			(stroke
				(width 0.1524)
				(type default)
			)
			(layer "F.SilkS")
		)
		(fp_line
			(start -0.7874 -0.4064)
			(end 0.7874 -0.4064)
			(stroke
				(width 0.1524)
				(type default)
			)
			(layer "F.SilkS")
		)
		(fp_line
			(start 0.7874 0.4064)
			(end -0.7874 0.4064)
			(stroke
				(width 0.1524)
				(type default)
			)
			(layer "F.SilkS")
		)
		(fp_line
			(start -0.7874 0.4064)
			(end -0.7874 -0.4064)
			(stroke
				(width 0.1524)
				(type default)
			)
			(layer "F.SilkS")
		)
		(fp_line
			(start -0.12065 -0.305054)
			(end -0.12065 -0.2794)
			(stroke
				(width 0.1)
				(type default)
			)
			(layer "F.Fab")
		)
		(fp_line
			(start -0.67945 -0.305054)
			(end -0.12065 -0.305054)
			(stroke
				(width 0.1)
				(type default)
			)
			(layer "F.Fab")
		)
		(fp_line
			(start 0.67945 -0.3048)
			(end 0.67945 0.3048)
			(stroke
				(width 0.1)
				(type default)
			)
			(layer "F.Fab")
		)
		(fp_line
			(start 0.12065 -0.3048)
			(end 0.67945 -0.3048)
			(stroke
				(width 0.1)
				(type default)
			)
			(layer "F.Fab")
		)
		(fp_line
			(start 0.12065 -0.2794)
			(end 0.12065 -0.3048)
			(stroke
				(width 0.1)
				(type default)
			)
			(layer "F.Fab")
		)
		(fp_line
			(start -0.12065 -0.2794)
			(end 0.12065 -0.2794)
			(stroke
				(width 0.1)
				(type default)
			)
			(layer "F.Fab")
		)
		(fp_line
			(start 0.120396 0.2794)
			(end -0.12065 0.2794)
			(stroke
				(width 0.1)
				(type default)
			)
			(layer "F.Fab")
		)
		(fp_line
			(start -0.12065 0.2794)
			(end -0.12065 0.3048)
			(stroke
				(width 0.1)
				(type default)
			)
			(layer "F.Fab")
		)
		(fp_line
			(start 0.67945 0.3048)
			(end 0.120396 0.3048)
			(stroke
				(width 0.1)
				(type default)
			)
			(layer "F.Fab")
		)
		(fp_line
			(start 0.120396 0.3048)
			(end 0.120396 0.2794)
			(stroke
				(width 0.1)
				(type default)
			)
			(layer "F.Fab")
		)
		(fp_line
			(start -0.12065 0.3048)
			(end -0.67945 0.3048)
			(stroke
				(width 0.1)
				(type default)
			)
			(layer "F.Fab")
		)
		(fp_line
			(start -0.67945 0.3048)
			(end -0.67945 -0.305054)
			(stroke
				(width 0.1)
				(type default)
			)
			(layer "F.Fab")
		)
		(pad "1" smd circle
			(at -0.40005 0 90)
			(size 0 0)
			(layers "F.Cu" "F.Mask" "F.Paste")
			(net "H_CPU1_THERMTRIP_LVC1_R_N")
		)
		(pad "2" smd circle
			(at 0.40005 0 90)
			(size 0 0)
			(layers "F.Cu" "F.Mask" "F.Paste")
			(net "H_CPU1_THERMTRIP_VT_R_N")
		)
	)
)
